# SCM (Grand Teton) — schematic netlist excerpt (pin names and nets, part order shuffled) for the footprints in the layout excerpt that follows; sources: Cadence DE-HDL packaged netlist, KiCad conversion of 12092022_DA0F0TMDCD0_F0T_Management_Board_D_brd_V3_OCP.brd

R655  Q_RES  10K 1% EMPTY  pkg 0402LF  page 21 : A = P3V3_AUX ; B = EMMC_DT0_R

U13  MC74VHC1G07DFT2G  EMPTY  pkg SC70-5XA  page 22
  NC1  = NC
  IN_A  = RST_BMC_SRST_BUF_R1_N
  GND  = GND
  OUT_Y  = RST_BMC_EXTRST_R1_N
  VCC  = P3V3_AUX

(kicad_pcb
	(version 20260206)
	(generator "pcbnew")
	(generator_version "10.0")
	(general
		(thickness 1.6)
		(legacy_teardrops no)
	)
	(paper "A4")
	(title_block
		(title "12092022_DA0F0TMDCD0_F0T_Management_Board_D_brd_V3_OCP.brd")
		(comment 1 "Grand Teton / footprints 603-604 of 1440")
	)
	(layers
		(0 "F.Cu" signal "TOP")
		(4 "In1.Cu" signal "GND")
		(6 "In2.Cu" signal "IN1")
		(8 "In3.Cu" signal "GND1")
		(10 "In4.Cu" signal "IN2")
		(12 "In5.Cu" signal "VCC")
		(14 "In6.Cu" signal "VCC1")
		(16 "In7.Cu" signal "IN3")
		(18 "In8.Cu" signal "GND2")
		(20 "In9.Cu" signal "IN4")
		(22 "In10.Cu" signal "GND3")
		(2 "B.Cu" signal "BOTTOM")
		(9 "F.Adhes" user "F.Adhesive")
		(11 "B.Adhes" user "B.Adhesive")
		(13 "F.Paste" user "Package Geometry/Pastemask Top")
		(15 "B.Paste" user "Package Geometry/Pastemask Bottom")
		(5 "F.SilkS" user "Ref Des/Silkscreen Top")
		(7 "B.SilkS" user "Ref Des/Silkscreen Bottom")
		(1 "F.Mask" user "Board Geometry/Soldermask Top")
		(3 "B.Mask" user "Board Geometry/Soldermask Bottom")
		(17 "Dwgs.User" user "User.Drawings")
		(19 "Cmts.User" user "User.Comments")
		(21 "Eco1.User" user "User.Eco1")
		(23 "Eco2.User" user "User.Eco2")
		(25 "Edge.Cuts" user "Board Geometry/Outline")
		(27 "Margin" user)
		(31 "F.CrtYd" user "Package Geometry/Place Bound Top")
		(29 "B.CrtYd" user "Package Geometry/Place Bound Bottom")
		(35 "F.Fab" user "Ref Des/Assembly Top")
		(33 "B.Fab" user "Ref Des/Assembly Bottom")
	)
	(footprint ""
		(layer "F.Cu")
		(at 14.113002 -106.33837)
		(property "Reference" "U13"
			(at 1.279398 1.81864 0)
			(unlocked yes)
			(layer "F.SilkS")
			(effects
				(font
					(size 0.7874 0.5842)
					(thickness 0.1524)
				)
				(justify left)
			)
		)
		(property "Value" ""
			(at 0 0 0)
			(layer "F.Fab")
			(effects
				(font
					(size 1.27 1.27)
				)
			)
		)
		(duplicate_pad_numbers_are_jumpers no)
		(fp_line
			(start -1.33096 -1.100074)
			(end -0.381 -1.100074)
			(stroke
				(width 0.1524)
				(type default)
			)
			(layer "F.SilkS")
		)
		(fp_line
			(start -1.33096 1.100074)
			(end -1.33096 -1.100074)
			(stroke
				(width 0.1524)
				(type default)
			)
			(layer "F.SilkS")
		)
		(fp_line
			(start -0.381 -1.100074)
			(end 0 -0.649986)
			(stroke
				(width 0.1524)
				(type default)
			)
			(layer "F.SilkS")
		)
		(fp_line
			(start 0 -0.649986)
			(end 0.381 -1.100074)
			(stroke
				(width 0.1524)
				(type default)
			)
			(layer "F.SilkS")
		)
		(fp_line
			(start 0.381 -1.100074)
			(end 1.33096 -1.100074)
			(stroke
				(width 0.1524)
				(type default)
			)
			(layer "F.SilkS")
		)
		(fp_line
			(start 1.33096 -1.100074)
			(end 1.33096 1.100074)
			(stroke
				(width 0.1524)
				(type default)
			)
			(layer "F.SilkS")
		)
		(fp_line
			(start 1.33096 1.100074)
			(end -1.33096 1.100074)
			(stroke
				(width 0.1524)
				(type default)
			)
			(layer "F.SilkS")
		)
		(fp_poly
			(pts
				(xy -2.209292 -0.902462) (xy -2.209292 -0.394462) (xy -1.447292 -0.648462)
			)
			(stroke
				(width 0)
				(type default)
			)
			(fill yes)
			(layer "F.SilkS")
		)
		(fp_line
			(start -0.674878 -1.100074)
			(end 0.674878 -1.100074)
			(stroke
				(width 0.1)
				(type default)
			)
			(layer "F.Fab")
		)
		(fp_line
			(start -0.674878 1.100074)
			(end -0.674878 -1.100074)
			(stroke
				(width 0.1)
				(type default)
			)
			(layer "F.Fab")
		)
		(fp_line
			(start 0.674878 -1.100074)
			(end 0.674878 1.100074)
			(stroke
				(width 0.1)
				(type default)
			)
			(layer "F.Fab")
		)
		(fp_line
			(start 0.674878 1.100074)
			(end -0.674878 1.100074)
			(stroke
				(width 0.1)
				(type default)
			)
			(layer "F.Fab")
		)
		(fp_poly
			(pts
				(xy -2.209292 -0.902462) (xy -2.209292 -0.394462) (xy -1.447292 -0.648462)
			)
			(stroke
				(width 0)
				(type default)
			)
			(fill yes)
			(layer "F.Fab")
		)
		(pad "1" smd rect
			(at -0.94996 -0.649986 90)
			(size 0.4064 0.508)
			(layers "F.Cu" "F.Mask" "F.Paste")
			(net "Net_317")
		)
		(pad "2" smd rect
			(at -0.94996 0 90)
			(size 0.4064 0.508)
			(layers "F.Cu" "F.Mask" "F.Paste")
			(net "RST_BMC_SRST_BUF_R1_N")
		)
		(pad "3" smd rect
			(at -0.94996 0.649986 90)
			(size 0.4064 0.508)
			(layers "F.Cu" "F.Mask" "F.Paste")
			(net "GND")
		)
		(pad "4" smd rect
			(at 0.94996 0.649986 90)
			(size 0.4064 0.508)
			(layers "F.Cu" "F.Mask" "F.Paste")
			(net "RST_BMC_EXTRST_R1_N")
		)
		(pad "5" smd rect
			(at 0.94996 -0.649986 90)
			(size 0.4064 0.508)
			(layers "F.Cu" "F.Mask" "F.Paste")
			(net "P3V3_AUX")
		)
	)
	(footprint ""
		(layer "F.Cu")
		(at 39.095172 -83.816952 -90)
		(property "Reference" "R655"
			(at 0 0 270)
			(layer "F.SilkS")
			(hide yes)
			(effects
				(font
					(size 1.27 1.27)
				)
			)
		)
		(property "Value" ""
			(at 0 0 270)
			(layer "F.Fab")
			(effects
				(font
					(size 1.27 1.27)
				)
			)
		)
		(duplicate_pad_numbers_are_jumpers no)
		(fp_line
			(start -0.7874 0.4064)
			(end -0.7874 -0.4064)
			(stroke
				(width 0.1524)
				(type default)
			)
			(layer "F.SilkS")
		)
		(fp_line
			(start 0.7874 0.4064)
			(end -0.7874 0.4064)
			(stroke
				(width 0.1524)
				(type default)
			)
			(layer "F.SilkS")
		)
		(fp_line
			(start -0.7874 -0.4064)
			(end 0.7874 -0.4064)
			(stroke
				(width 0.1524)
				(type default)
			)
			(layer "F.SilkS")
		)
		(fp_line
			(start 0.7874 -0.4064)
			(end 0.7874 0.4064)
			(stroke
				(width 0.1524)
				(type default)
			)
			(layer "F.SilkS")
		)
		(fp_line
			(start -0.67945 0.3048)
			(end -0.67945 -0.305054)
			(stroke
				(width 0.1)
				(type default)
			)
			(layer "F.Fab")
		)
		(fp_line
			(start -0.12065 0.3048)
			(end -0.67945 0.3048)
			(stroke
				(width 0.1)
				(type default)
			)
			(layer "F.Fab")
		)
		(fp_line
			(start 0.120396 0.3048)
			(end 0.120396 0.2794)
			(stroke
				(width 0.1)
				(type default)
			)
			(layer "F.Fab")
		)
		(fp_line
			(start 0.67945 0.3048)
			(end 0.120396 0.3048)
			(stroke
				(width 0.1)
				(type default)
			)
			(layer "F.Fab")
		)
		(fp_line
			(start -0.12065 0.2794)
			(end -0.12065 0.3048)
			(stroke
				(width 0.1)
				(type default)
			)
			(layer "F.Fab")
		)
		(fp_line
			(start 0.120396 0.2794)
			(end -0.12065 0.2794)
			(stroke
				(width 0.1)
				(type default)
			)
			(layer "F.Fab")
		)
		(fp_line
			(start -0.12065 -0.2794)
			(end 0.12065 -0.2794)
			(stroke
				(width 0.1)
				(type default)
			)
			(layer "F.Fab")
		)
		(fp_line
			(start 0.12065 -0.2794)
			(end 0.12065 -0.3048)
			(stroke
				(width 0.1)
				(type default)
			)
			(layer "F.Fab")
		)
		(fp_line
			(start 0.12065 -0.3048)
			(end 0.67945 -0.3048)
			(stroke
				(width 0.1)
				(type default)
			)
			(layer "F.Fab")
		)
		(fp_line
			(start 0.67945 -0.3048)
			(end 0.67945 0.3048)
			(stroke
				(width 0.1)
				(type default)
			)
			(layer "F.Fab")
		)
		(fp_line
			(start -0.67945 -0.305054)
			(end -0.12065 -0.305054)
			(stroke
				(width 0.1)
				(type default)
			)
			(layer "F.Fab")
		)
		(fp_line
			(start -0.12065 -0.305054)
			(end -0.12065 -0.2794)
			(stroke
				(width 0.1)
				(type default)
			)
			(layer "F.Fab")
		)
		(pad "1" smd circle
			(at -0.40005 0 270)
			(size 0 0)
			(layers "F.Cu" "F.Mask" "F.Paste")
			(net "P3V3_AUX")
		)
		(pad "2" smd circle
			(at 0.40005 0 270)
			(size 0 0)
			(layers "F.Cu" "F.Mask" "F.Paste")
			(net "EMMC_DT0_R")
		)
	)
)
